# S9S_MB_2U (Grand Teton) — schematic netlist excerpt (pin names and nets, part order shuffled) for the footprints in the layout excerpt that follows; sources: Cadence DE-HDL packaged netlist, KiCad conversion of 03242023_DA0F0TMBIJ0_F0T_Motherboard_J_brd_V01_OCP.brd

C2378  Q_CAP  0.1UF 25V 10% X7R  pkg 0402  page 191 : A = P3V3_E1S_0 ; B = GND
PC1658  Q_CAP  100NF 50V 10% X7R  pkg C0402  page 290 : A = P12V_AUX ; B = GND
C936  Q_CAP_DIFFBUS  DIFF BUS_0.22UF 6.3V 20% X6S  pkg C0201  page 173 : \1\ = P5E_CPU0_PE2_TX_C_DN<14> ; \2\ = P5E_CPU0_PE2_TX_DN<14>

(kicad_pcb
	(version 20260206)
	(generator "pcbnew")
	(generator_version "10.0")
	(general
		(thickness 1.6)
		(legacy_teardrops no)
	)
	(paper "A4")
	(title_block
		(title "03242023_DA0F0TMBIJ0_F0T_Motherboard_J_brd_V01_OCP.brd")
		(comment 1 "Grand Teton / footprints 1994-1996 of 6105")
	)
	(layers
		(0 "F.Cu" signal "TOP")
		(4 "In1.Cu" signal "GND")
		(6 "In2.Cu" signal "IN1")
		(8 "In3.Cu" signal "GND1")
		(10 "In4.Cu" signal "IN2")
		(12 "In5.Cu" signal "GND2")
		(14 "In6.Cu" signal "IN3")
		(16 "In7.Cu" signal "GND3")
		(18 "In8.Cu" signal "VCC")
		(20 "In9.Cu" signal "VCC1")
		(22 "In10.Cu" signal "GND4")
		(24 "In11.Cu" signal "IN4")
		(26 "In12.Cu" signal "GND5")
		(28 "In13.Cu" signal "IN5")
		(30 "In14.Cu" signal "GND6")
		(32 "In15.Cu" signal "IN6")
		(34 "In16.Cu" signal "GND7")
		(2 "B.Cu" signal "BOTTOM")
		(9 "F.Adhes" user "F.Adhesive")
		(11 "B.Adhes" user "B.Adhesive")
		(13 "F.Paste" user "Package Geometry/Pastemask Top")
		(15 "B.Paste" user "Package Geometry/Pastemask Bottom")
		(5 "F.SilkS" user "Ref Des/Silkscreen Top")
		(7 "B.SilkS" user "Ref Des/Silkscreen Bottom")
		(1 "F.Mask" user "Board Geometry/Soldermask Top")
		(3 "B.Mask" user "Board Geometry/Soldermask Bottom")
		(17 "Dwgs.User" user "User.Drawings")
		(19 "Cmts.User" user "User.Comments")
		(21 "Eco1.User" user "User.Eco1")
		(23 "Eco2.User" user "User.Eco2")
		(25 "Edge.Cuts" user "Board Geometry/Outline")
		(27 "Margin" user)
		(31 "F.CrtYd" user "Package Geometry/Place Bound Top")
		(29 "B.CrtYd" user "Package Geometry/Place Bound Bottom")
		(35 "F.Fab" user "Ref Des/Assembly Top")
		(33 "B.Fab" user "Ref Des/Assembly Bottom")
	)
	(footprint ""
		(layer "F.Cu")
		(at 173.5836 -366.33023)
		(property "Reference" "PC1658"
			(at 0 0 0)
			(layer "F.SilkS")
			(hide yes)
			(effects
				(font
					(size 1.27 1.27)
				)
			)
		)
		(property "Value" ""
			(at 0 0 0)
			(layer "F.Fab")
			(effects
				(font
					(size 1.27 1.27)
				)
			)
		)
		(duplicate_pad_numbers_are_jumpers no)
		(fp_line
			(start -0.7874 -0.4064)
			(end 0.7874 -0.4064)
			(stroke
				(width 0.1524)
				(type default)
			)
			(layer "F.SilkS")
		)
		(fp_line
			(start -0.7874 0.4064)
			(end -0.7874 -0.4064)
			(stroke
				(width 0.1524)
				(type default)
			)
			(layer "F.SilkS")
		)
		(fp_line
			(start 0.7874 -0.4064)
			(end 0.7874 0.4064)
			(stroke
				(width 0.1524)
				(type default)
			)
			(layer "F.SilkS")
		)
		(fp_line
			(start 0.7874 0.4064)
			(end -0.7874 0.4064)
			(stroke
				(width 0.1524)
				(type default)
			)
			(layer "F.SilkS")
		)
		(fp_line
			(start -0.67945 -0.305054)
			(end -0.12065 -0.305054)
			(stroke
				(width 0.1)
				(type default)
			)
			(layer "F.Fab")
		)
		(fp_line
			(start -0.67945 0.3048)
			(end -0.67945 -0.305054)
			(stroke
				(width 0.1)
				(type default)
			)
			(layer "F.Fab")
		)
		(fp_line
			(start -0.12065 -0.305054)
			(end -0.12065 -0.2794)
			(stroke
				(width 0.1)
				(type default)
			)
			(layer "F.Fab")
		)
		(fp_line
			(start -0.12065 -0.2794)
			(end 0.12065 -0.2794)
			(stroke
				(width 0.1)
				(type default)
			)
			(layer "F.Fab")
		)
		(fp_line
			(start -0.12065 0.2794)
			(end -0.12065 0.3048)
			(stroke
				(width 0.1)
				(type default)
			)
			(layer "F.Fab")
		)
		(fp_line
			(start -0.12065 0.3048)
			(end -0.67945 0.3048)
			(stroke
				(width 0.1)
				(type default)
			)
			(layer "F.Fab")
		)
		(fp_line
			(start 0.120396 0.2794)
			(end -0.12065 0.2794)
			(stroke
				(width 0.1)
				(type default)
			)
			(layer "F.Fab")
		)
		(fp_line
			(start 0.120396 0.3048)
			(end 0.120396 0.2794)
			(stroke
				(width 0.1)
				(type default)
			)
			(layer "F.Fab")
		)
		(fp_line
			(start 0.12065 -0.3048)
			(end 0.67945 -0.3048)
			(stroke
				(width 0.1)
				(type default)
			)
			(layer "F.Fab")
		)
		(fp_line
			(start 0.12065 -0.2794)
			(end 0.12065 -0.3048)
			(stroke
				(width 0.1)
				(type default)
			)
			(layer "F.Fab")
		)
		(fp_line
			(start 0.67945 -0.3048)
			(end 0.67945 0.3048)
			(stroke
				(width 0.1)
				(type default)
			)
			(layer "F.Fab")
		)
		(fp_line
			(start 0.67945 0.3048)
			(end 0.120396 0.3048)
			(stroke
				(width 0.1)
				(type default)
			)
			(layer "F.Fab")
		)
		(pad "1" smd circle
			(at -0.40005 0)
			(size 0 0)
			(layers "F.Cu" "F.Mask" "F.Paste")
			(net "P12V_AUX")
		)
		(pad "2" smd circle
			(at 0.40005 0)
			(size 0 0)
			(layers "F.Cu" "F.Mask" "F.Paste")
			(net "GND")
		)
	)
	(footprint ""
		(layer "F.Cu")
		(at 220.345 -49.911 180)
		(property "Reference" "C2378"
			(at 0 0 180)
			(layer "F.SilkS")
			(hide yes)
			(effects
				(font
					(size 1.27 1.27)
				)
			)
		)
		(property "Value" ""
			(at 0 0 180)
			(layer "F.Fab")
			(effects
				(font
					(size 1.27 1.27)
				)
			)
		)
		(duplicate_pad_numbers_are_jumpers no)
		(fp_line
			(start 0.7874 0.4064)
			(end -0.7874 0.4064)
			(stroke
				(width 0.1524)
				(type default)
			)
			(layer "F.SilkS")
		)
		(fp_line
			(start 0.7874 -0.4064)
			(end 0.7874 0.4064)
			(stroke
				(width 0.1524)
				(type default)
			)
			(layer "F.SilkS")
		)
		(fp_line
			(start -0.7874 0.4064)
			(end -0.7874 -0.4064)
			(stroke
				(width 0.1524)
				(type default)
			)
			(layer "F.SilkS")
		)
		(fp_line
			(start -0.7874 -0.4064)
			(end 0.7874 -0.4064)
			(stroke
				(width 0.1524)
				(type default)
			)
			(layer "F.SilkS")
		)
		(fp_line
			(start 0.67945 0.3048)
			(end 0.120396 0.3048)
			(stroke
				(width 0.1)
				(type default)
			)
			(layer "F.Fab")
		)
		(fp_line
			(start 0.67945 -0.3048)
			(end 0.67945 0.3048)
			(stroke
				(width 0.1)
				(type default)
			)
			(layer "F.Fab")
		)
		(fp_line
			(start 0.12065 -0.2794)
			(end 0.12065 -0.3048)
			(stroke
				(width 0.1)
				(type default)
			)
			(layer "F.Fab")
		)
		(fp_line
			(start 0.12065 -0.3048)
			(end 0.67945 -0.3048)
			(stroke
				(width 0.1)
				(type default)
			)
			(layer "F.Fab")
		)
		(fp_line
			(start 0.120396 0.3048)
			(end 0.120396 0.2794)
			(stroke
				(width 0.1)
				(type default)
			)
			(layer "F.Fab")
		)
		(fp_line
			(start 0.120396 0.2794)
			(end -0.12065 0.2794)
			(stroke
				(width 0.1)
				(type default)
			)
			(layer "F.Fab")
		)
		(fp_line
			(start -0.12065 0.3048)
			(end -0.67945 0.3048)
			(stroke
				(width 0.1)
				(type default)
			)
			(layer "F.Fab")
		)
		(fp_line
			(start -0.12065 0.2794)
			(end -0.12065 0.3048)
			(stroke
				(width 0.1)
				(type default)
			)
			(layer "F.Fab")
		)
		(fp_line
			(start -0.12065 -0.2794)
			(end 0.12065 -0.2794)
			(stroke
				(width 0.1)
				(type default)
			)
			(layer "F.Fab")
		)
		(fp_line
			(start -0.12065 -0.305054)
			(end -0.12065 -0.2794)
			(stroke
				(width 0.1)
				(type default)
			)
			(layer "F.Fab")
		)
		(fp_line
			(start -0.67945 0.3048)
			(end -0.67945 -0.305054)
			(stroke
				(width 0.1)
				(type default)
			)
			(layer "F.Fab")
		)
		(fp_line
			(start -0.67945 -0.305054)
			(end -0.12065 -0.305054)
			(stroke
				(width 0.1)
				(type default)
			)
			(layer "F.Fab")
		)
		(pad "1" smd circle
			(at -0.40005 0 180)
			(size 0 0)
			(layers "F.Cu" "F.Mask" "F.Paste")
			(net "P3V3_E1S_0")
		)
		(pad "2" smd circle
			(at 0.40005 0 180)
			(size 0 0)
			(layers "F.Cu" "F.Mask" "F.Paste")
			(net "GND")
		)
	)
	(footprint ""
		(layer "F.Cu")
		(at 375.37517 -402.371052 -90)
		(property "Reference" "C936"
			(at 0 0 270)
			(layer "F.SilkS")
			(hide yes)
			(effects
				(font
					(size 1.27 1.27)
				)
			)
		)
		(property "Value" ""
			(at 0 0 270)
			(layer "F.Fab")
			(effects
				(font
					(size 1.27 1.27)
				)
			)
		)
		(duplicate_pad_numbers_are_jumpers no)
		(fp_line
			(start -0.299974 0.150114)
			(end -0.299974 -0.150114)
			(stroke
				(width 0.1)
				(type default)
			)
			(layer "F.Fab")
		)
		(fp_line
			(start 0.299974 0.150114)
			(end -0.299974 0.150114)
			(stroke
				(width 0.1)
				(type default)
			)
			(layer "F.Fab")
		)
		(fp_line
			(start -0.299974 -0.150114)
			(end 0.299974 -0.150114)
			(stroke
				(width 0.1)
				(type default)
			)
			(layer "F.Fab")
		)
		(fp_line
			(start 0.299974 -0.150114)
			(end 0.299974 0.150114)
			(stroke
				(width 0.1)
				(type default)
			)
			(layer "F.Fab")
		)
		(pad "1" smd rect
			(at -0.2667 0 270)
			(size 0.3048 0.381)
			(layers "F.Cu" "F.Mask" "F.Paste")
			(net "P5E_CPU0_PE2_TX_C_DN<14>")
		)
		(pad "2" smd rect
			(at 0.2667 0 270)
			(size 0.3048 0.381)
			(layers "F.Cu" "F.Mask" "F.Paste")
			(net "P5E_CPU0_PE2_TX_DN<14>")
		)
	)
)
